# T6G (Grand Teton) — schematic netlist excerpt (pin names and nets, part order shuffled) for the footprints in the layout excerpt that follows; sources: Cadence DE-HDL packaged netlist, KiCad conversion of 04192023_DAF0TMB3IC0_F0TG_MB_C_brd_V02_OCP.brd

R546  Q_RES  4.7K 5% CHIP  pkg 0402LF  page 55 : A = FM_BMC_TPM_PRES_N ; B = PVDD18_S5_P1
C658  Q_CAP  0.1UF 10V 10% X7S  pkg C0201  page 290 : A = P0V9_CPU0_RT1_2A ; B = GND
C262  Q_CAP  22UF 4V 20% X6S  pkg C0402  page 323 : A = P0V9_CPU1_RT0_2A ; B = GND

(kicad_pcb
	(version 20260206)
	(generator "pcbnew")
	(generator_version "10.0")
	(general
		(thickness 1.6)
		(legacy_teardrops no)
	)
	(paper "A4")
	(title_block
		(title "04192023_DAF0TMB3IC0_F0TG_MB_C_brd_V02_OCP.brd")
		(comment 1 "Grand Teton / footprints 8197-8199 of 8354")
	)
	(layers
		(0 "F.Cu" signal "TOP")
		(4 "In1.Cu" signal "GND")
		(6 "In2.Cu" signal "IN1")
		(8 "In3.Cu" signal "GND1")
		(10 "In4.Cu" signal "IN2")
		(12 "In5.Cu" signal "GND2")
		(14 "In6.Cu" signal "IN3")
		(16 "In7.Cu" signal "GND3")
		(18 "In8.Cu" signal "VCC")
		(20 "In9.Cu" signal "VCC1")
		(22 "In10.Cu" signal "GND4")
		(24 "In11.Cu" signal "IN4")
		(26 "In12.Cu" signal "GND5")
		(28 "In13.Cu" signal "IN5")
		(30 "In14.Cu" signal "GND6")
		(32 "In15.Cu" signal "IN6")
		(34 "In16.Cu" signal "GND7")
		(2 "B.Cu" signal "BOTTOM")
		(9 "F.Adhes" user "F.Adhesive")
		(11 "B.Adhes" user "B.Adhesive")
		(13 "F.Paste" user "Package Geometry/Pastemask Top")
		(15 "B.Paste" user "Package Geometry/Pastemask Bottom")
		(5 "F.SilkS" user "Ref Des/Silkscreen Top")
		(7 "B.SilkS" user "Ref Des/Silkscreen Bottom")
		(1 "F.Mask" user "Board Geometry/Soldermask Top")
		(3 "B.Mask" user "Board Geometry/Soldermask Bottom")
		(17 "Dwgs.User" user "User.Drawings")
		(19 "Cmts.User" user "User.Comments")
		(21 "Eco1.User" user "User.Eco1")
		(23 "Eco2.User" user "User.Eco2")
		(25 "Edge.Cuts" user "Board Geometry/Outline")
		(27 "Margin" user)
		(31 "F.CrtYd" user "Package Geometry/Place Bound Top")
		(29 "B.CrtYd" user "Package Geometry/Place Bound Bottom")
		(35 "F.Fab" user "Ref Des/Assembly Top")
		(33 "B.Fab" user "Ref Des/Assembly Bottom")
	)
	(footprint ""
		(layer "B.Cu")
		(at 144.932654 -316.47511 180)
		(property "Reference" "R546"
			(at 0 0 0)
			(layer "B.SilkS")
			(hide yes)
			(effects
				(font
					(size 1.27 1.27)
				)
				(justify mirror)
			)
		)
		(property "Value" ""
			(at 0 0 0)
			(layer "B.Fab")
			(effects
				(font
					(size 1.27 1.27)
				)
				(justify mirror)
			)
		)
		(duplicate_pad_numbers_are_jumpers no)
		(fp_line
			(start 0.7874 0.4064)
			(end 0.7874 -0.4064)
			(stroke
				(width 0.1524)
				(type default)
			)
			(layer "B.SilkS")
		)
		(fp_line
			(start 0.7874 -0.4064)
			(end -0.7874 -0.4064)
			(stroke
				(width 0.1524)
				(type default)
			)
			(layer "B.SilkS")
		)
		(fp_line
			(start -0.7874 0.4064)
			(end 0.7874 0.4064)
			(stroke
				(width 0.1524)
				(type default)
			)
			(layer "B.SilkS")
		)
		(fp_line
			(start -0.7874 -0.4064)
			(end -0.7874 0.4064)
			(stroke
				(width 0.1524)
				(type default)
			)
			(layer "B.SilkS")
		)
		(fp_line
			(start 0.67945 0.3048)
			(end 0.67945 -0.305054)
			(stroke
				(width 0.1)
				(type default)
			)
			(layer "B.Fab")
		)
		(fp_line
			(start 0.67945 -0.305054)
			(end 0.12065 -0.305054)
			(stroke
				(width 0.1)
				(type default)
			)
			(layer "B.Fab")
		)
		(fp_line
			(start 0.12065 0.3048)
			(end 0.67945 0.3048)
			(stroke
				(width 0.1)
				(type default)
			)
			(layer "B.Fab")
		)
		(fp_line
			(start 0.12065 0.2794)
			(end 0.12065 0.3048)
			(stroke
				(width 0.1)
				(type default)
			)
			(layer "B.Fab")
		)
		(fp_line
			(start 0.12065 -0.2794)
			(end -0.12065 -0.2794)
			(stroke
				(width 0.1)
				(type default)
			)
			(layer "B.Fab")
		)
		(fp_line
			(start 0.12065 -0.305054)
			(end 0.12065 -0.2794)
			(stroke
				(width 0.1)
				(type default)
			)
			(layer "B.Fab")
		)
		(fp_line
			(start -0.120396 0.3048)
			(end -0.120396 0.2794)
			(stroke
				(width 0.1)
				(type default)
			)
			(layer "B.Fab")
		)
		(fp_line
			(start -0.120396 0.2794)
			(end 0.12065 0.2794)
			(stroke
				(width 0.1)
				(type default)
			)
			(layer "B.Fab")
		)
		(fp_line
			(start -0.12065 -0.2794)
			(end -0.12065 -0.3048)
			(stroke
				(width 0.1)
				(type default)
			)
			(layer "B.Fab")
		)
		(fp_line
			(start -0.12065 -0.3048)
			(end -0.67945 -0.3048)
			(stroke
				(width 0.1)
				(type default)
			)
			(layer "B.Fab")
		)
		(fp_line
			(start -0.67945 0.3048)
			(end -0.120396 0.3048)
			(stroke
				(width 0.1)
				(type default)
			)
			(layer "B.Fab")
		)
		(fp_line
			(start -0.67945 -0.3048)
			(end -0.67945 0.3048)
			(stroke
				(width 0.1)
				(type default)
			)
			(layer "B.Fab")
		)
		(pad "1" smd circle
			(at 0.40005 0)
			(size 0 0)
			(layers "B.Cu" "B.Mask" "B.Paste")
			(net "FM_BMC_TPM_PRES_N")
		)
		(pad "2" smd circle
			(at -0.40005 0)
			(size 0 0)
			(layers "B.Cu" "B.Mask" "B.Paste")
			(net "PVDD18_S5_P1")
		)
	)
	(footprint ""
		(layer "B.Cu")
		(at 66.745358 -390.560052 90)
		(property "Reference" "C262"
			(at 0 0 90)
			(layer "B.SilkS")
			(hide yes)
			(effects
				(font
					(size 1.27 1.27)
				)
				(justify mirror)
			)
		)
		(property "Value" ""
			(at 0 0 90)
			(layer "B.Fab")
			(effects
				(font
					(size 1.27 1.27)
				)
				(justify mirror)
			)
		)
		(duplicate_pad_numbers_are_jumpers no)
		(fp_line
			(start 0.7874 -0.4064)
			(end -0.7874 -0.4064)
			(stroke
				(width 0.1524)
				(type default)
			)
			(layer "B.SilkS")
		)
		(fp_line
			(start -0.7874 -0.4064)
			(end -0.7874 0.4064)
			(stroke
				(width 0.1524)
				(type default)
			)
			(layer "B.SilkS")
		)
		(fp_line
			(start 0.7874 0.4064)
			(end 0.7874 -0.4064)
			(stroke
				(width 0.1524)
				(type default)
			)
			(layer "B.SilkS")
		)
		(fp_line
			(start -0.7874 0.4064)
			(end 0.7874 0.4064)
			(stroke
				(width 0.1524)
				(type default)
			)
			(layer "B.SilkS")
		)
		(fp_line
			(start 0.67945 -0.305054)
			(end 0.12065 -0.305054)
			(stroke
				(width 0.1)
				(type default)
			)
			(layer "B.Fab")
		)
		(fp_line
			(start 0.12065 -0.305054)
			(end 0.12065 -0.2794)
			(stroke
				(width 0.1)
				(type default)
			)
			(layer "B.Fab")
		)
		(fp_line
			(start -0.12065 -0.3048)
			(end -0.67945 -0.3048)
			(stroke
				(width 0.1)
				(type default)
			)
			(layer "B.Fab")
		)
		(fp_line
			(start -0.67945 -0.3048)
			(end -0.67945 0.3048)
			(stroke
				(width 0.1)
				(type default)
			)
			(layer "B.Fab")
		)
		(fp_line
			(start 0.12065 -0.2794)
			(end -0.12065 -0.2794)
			(stroke
				(width 0.1)
				(type default)
			)
			(layer "B.Fab")
		)
		(fp_line
			(start -0.12065 -0.2794)
			(end -0.12065 -0.3048)
			(stroke
				(width 0.1)
				(type default)
			)
			(layer "B.Fab")
		)
		(fp_line
			(start 0.12065 0.2794)
			(end 0.12065 0.3048)
			(stroke
				(width 0.1)
				(type default)
			)
			(layer "B.Fab")
		)
		(fp_line
			(start -0.120396 0.2794)
			(end 0.12065 0.2794)
			(stroke
				(width 0.1)
				(type default)
			)
			(layer "B.Fab")
		)
		(fp_line
			(start 0.67945 0.3048)
			(end 0.67945 -0.305054)
			(stroke
				(width 0.1)
				(type default)
			)
			(layer "B.Fab")
		)
		(fp_line
			(start 0.12065 0.3048)
			(end 0.67945 0.3048)
			(stroke
				(width 0.1)
				(type default)
			)
			(layer "B.Fab")
		)
		(fp_line
			(start -0.120396 0.3048)
			(end -0.120396 0.2794)
			(stroke
				(width 0.1)
				(type default)
			)
			(layer "B.Fab")
		)
		(fp_line
			(start -0.67945 0.3048)
			(end -0.120396 0.3048)
			(stroke
				(width 0.1)
				(type default)
			)
			(layer "B.Fab")
		)
		(pad "1" smd circle
			(at 0.40005 0 270)
			(size 0 0)
			(layers "B.Cu" "B.Mask" "B.Paste")
			(net "P0V9_CPU1_RT0_2A")
		)
		(pad "2" smd circle
			(at -0.40005 0 270)
			(size 0 0)
			(layers "B.Cu" "B.Mask" "B.Paste")
			(net "GND")
		)
	)
	(footprint ""
		(layer "B.Cu")
		(at 355.944932 -396.150592 180)
		(property "Reference" "C658"
			(at 0 0 0)
			(layer "B.SilkS")
			(hide yes)
			(effects
				(font
					(size 1.27 1.27)
				)
				(justify mirror)
			)
		)
		(property "Value" ""
			(at 0 0 0)
			(layer "B.Fab")
			(effects
				(font
					(size 1.27 1.27)
				)
				(justify mirror)
			)
		)
		(duplicate_pad_numbers_are_jumpers no)
		(fp_line
			(start 0.299974 0.150114)
			(end 0.299974 -0.150114)
			(stroke
				(width 0.1)
				(type default)
			)
			(layer "B.Fab")
		)
		(fp_line
			(start 0.299974 -0.150114)
			(end -0.299974 -0.150114)
			(stroke
				(width 0.1)
				(type default)
			)
			(layer "B.Fab")
		)
		(fp_line
			(start -0.299974 0.150114)
			(end 0.299974 0.150114)
			(stroke
				(width 0.1)
				(type default)
			)
			(layer "B.Fab")
		)
		(fp_line
			(start -0.299974 -0.150114)
			(end -0.299974 0.150114)
			(stroke
				(width 0.1)
				(type default)
			)
			(layer "B.Fab")
		)
		(pad "1" smd rect
			(at 0.2667 0)
			(size 0.3048 0.381)
			(layers "B.Cu" "B.Mask" "B.Paste")
			(net "P0V9_CPU0_RT1_2A")
		)
		(pad "2" smd rect
			(at -0.2667 0)
			(size 0.3048 0.381)
			(layers "B.Cu" "B.Mask" "B.Paste")
			(net "GND")
		)
	)
)
